# T6G (Grand Teton) — schematic netlist excerpt (pin names and nets, part order shuffled) for the footprints in the layout excerpt that follows; sources: Cadence DE-HDL packaged netlist, KiCad conversion of 04192023_DAF0TMB3IC0_F0TG_MB_C_brd_V02_OCP.brd

PR3002  Q_RES  0 5% CHIP  pkg 0402LF  page 268 : A = GND ; B = AGND_HSC
PR372  Q_RES  5.6 1% CHIP  pkg 0402LF  page 223 : A = SW_PVDDIO_P1_BOOT4 ; B = SW_PVDDIO_P1_BOOT4_R
R915  Q_RES  4.7K 5% EMPTY  pkg 0201LF  page 353 : A = P1V8_CPU1_RT_1D ; B = GPIO2_RT_CPU1_P3

(kicad_pcb
	(version 20260206)
	(generator "pcbnew")
	(generator_version "10.0")
	(general
		(thickness 1.6)
		(legacy_teardrops no)
	)
	(paper "A4")
	(title_block
		(title "04192023_DAF0TMB3IC0_F0TG_MB_C_brd_V02_OCP.brd")
		(comment 1 "Grand Teton / footprints 860-862 of 8354")
	)
	(layers
		(0 "F.Cu" signal "TOP")
		(4 "In1.Cu" signal "GND")
		(6 "In2.Cu" signal "IN1")
		(8 "In3.Cu" signal "GND1")
		(10 "In4.Cu" signal "IN2")
		(12 "In5.Cu" signal "GND2")
		(14 "In6.Cu" signal "IN3")
		(16 "In7.Cu" signal "GND3")
		(18 "In8.Cu" signal "VCC")
		(20 "In9.Cu" signal "VCC1")
		(22 "In10.Cu" signal "GND4")
		(24 "In11.Cu" signal "IN4")
		(26 "In12.Cu" signal "GND5")
		(28 "In13.Cu" signal "IN5")
		(30 "In14.Cu" signal "GND6")
		(32 "In15.Cu" signal "IN6")
		(34 "In16.Cu" signal "GND7")
		(2 "B.Cu" signal "BOTTOM")
		(9 "F.Adhes" user "F.Adhesive")
		(11 "B.Adhes" user "B.Adhesive")
		(13 "F.Paste" user "Package Geometry/Pastemask Top")
		(15 "B.Paste" user "Package Geometry/Pastemask Bottom")
		(5 "F.SilkS" user "Ref Des/Silkscreen Top")
		(7 "B.SilkS" user "Ref Des/Silkscreen Bottom")
		(1 "F.Mask" user "Board Geometry/Soldermask Top")
		(3 "B.Mask" user "Board Geometry/Soldermask Bottom")
		(17 "Dwgs.User" user "User.Drawings")
		(19 "Cmts.User" user "User.Comments")
		(21 "Eco1.User" user "User.Eco1")
		(23 "Eco2.User" user "User.Eco2")
		(25 "Edge.Cuts" user "Board Geometry/Outline")
		(27 "Margin" user)
		(31 "F.CrtYd" user "Package Geometry/Place Bound Top")
		(29 "B.CrtYd" user "Package Geometry/Place Bound Bottom")
		(35 "F.Fab" user "Ref Des/Assembly Top")
		(33 "B.Fab" user "Ref Des/Assembly Bottom")
	)
	(footprint ""
		(layer "F.Cu")
		(at 178.71694 -401.452842)
		(property "Reference" "PR3002"
			(at 0 0 0)
			(layer "F.SilkS")
			(hide yes)
			(effects
				(font
					(size 1.27 1.27)
				)
			)
		)
		(property "Value" ""
			(at 0 0 0)
			(layer "F.Fab")
			(effects
				(font
					(size 1.27 1.27)
				)
			)
		)
		(duplicate_pad_numbers_are_jumpers no)
		(fp_line
			(start -0.7874 -0.4064)
			(end 0.7874 -0.4064)
			(stroke
				(width 0.1524)
				(type default)
			)
			(layer "F.SilkS")
		)
		(fp_line
			(start -0.7874 0.4064)
			(end -0.7874 -0.4064)
			(stroke
				(width 0.1524)
				(type default)
			)
			(layer "F.SilkS")
		)
		(fp_line
			(start 0.7874 -0.4064)
			(end 0.7874 0.4064)
			(stroke
				(width 0.1524)
				(type default)
			)
			(layer "F.SilkS")
		)
		(fp_line
			(start 0.7874 0.4064)
			(end -0.7874 0.4064)
			(stroke
				(width 0.1524)
				(type default)
			)
			(layer "F.SilkS")
		)
		(fp_line
			(start -0.67945 -0.305054)
			(end -0.12065 -0.305054)
			(stroke
				(width 0.1)
				(type default)
			)
			(layer "F.Fab")
		)
		(fp_line
			(start -0.67945 0.3048)
			(end -0.67945 -0.305054)
			(stroke
				(width 0.1)
				(type default)
			)
			(layer "F.Fab")
		)
		(fp_line
			(start -0.12065 -0.305054)
			(end -0.12065 -0.2794)
			(stroke
				(width 0.1)
				(type default)
			)
			(layer "F.Fab")
		)
		(fp_line
			(start -0.12065 -0.2794)
			(end 0.12065 -0.2794)
			(stroke
				(width 0.1)
				(type default)
			)
			(layer "F.Fab")
		)
		(fp_line
			(start -0.12065 0.2794)
			(end -0.12065 0.3048)
			(stroke
				(width 0.1)
				(type default)
			)
			(layer "F.Fab")
		)
		(fp_line
			(start -0.12065 0.3048)
			(end -0.67945 0.3048)
			(stroke
				(width 0.1)
				(type default)
			)
			(layer "F.Fab")
		)
		(fp_line
			(start 0.120396 0.2794)
			(end -0.12065 0.2794)
			(stroke
				(width 0.1)
				(type default)
			)
			(layer "F.Fab")
		)
		(fp_line
			(start 0.120396 0.3048)
			(end 0.120396 0.2794)
			(stroke
				(width 0.1)
				(type default)
			)
			(layer "F.Fab")
		)
		(fp_line
			(start 0.12065 -0.3048)
			(end 0.67945 -0.3048)
			(stroke
				(width 0.1)
				(type default)
			)
			(layer "F.Fab")
		)
		(fp_line
			(start 0.12065 -0.2794)
			(end 0.12065 -0.3048)
			(stroke
				(width 0.1)
				(type default)
			)
			(layer "F.Fab")
		)
		(fp_line
			(start 0.67945 -0.3048)
			(end 0.67945 0.3048)
			(stroke
				(width 0.1)
				(type default)
			)
			(layer "F.Fab")
		)
		(fp_line
			(start 0.67945 0.3048)
			(end 0.120396 0.3048)
			(stroke
				(width 0.1)
				(type default)
			)
			(layer "F.Fab")
		)
		(pad "1" smd circle
			(at -0.40005 0)
			(size 0 0)
			(layers "F.Cu" "F.Mask" "F.Paste")
			(net "GND")
		)
		(pad "2" smd circle
			(at 0.40005 0)
			(size 0 0)
			(layers "F.Cu" "F.Mask" "F.Paste")
			(net "AGND_HSC")
		)
	)
	(footprint ""
		(layer "F.Cu")
		(at 29.35986 -351.372932 90)
		(property "Reference" "PR372"
			(at 0 0 90)
			(layer "F.SilkS")
			(hide yes)
			(effects
				(font
					(size 1.27 1.27)
				)
			)
		)
		(property "Value" ""
			(at 0 0 90)
			(layer "F.Fab")
			(effects
				(font
					(size 1.27 1.27)
				)
			)
		)
		(duplicate_pad_numbers_are_jumpers no)
		(fp_line
			(start 0.7874 -0.4064)
			(end 0.7874 0.4064)
			(stroke
				(width 0.1524)
				(type default)
			)
			(layer "F.SilkS")
		)
		(fp_line
			(start -0.7874 -0.4064)
			(end 0.7874 -0.4064)
			(stroke
				(width 0.1524)
				(type default)
			)
			(layer "F.SilkS")
		)
		(fp_line
			(start 0.7874 0.4064)
			(end -0.7874 0.4064)
			(stroke
				(width 0.1524)
				(type default)
			)
			(layer "F.SilkS")
		)
		(fp_line
			(start -0.7874 0.4064)
			(end -0.7874 -0.4064)
			(stroke
				(width 0.1524)
				(type default)
			)
			(layer "F.SilkS")
		)
		(fp_line
			(start -0.12065 -0.305054)
			(end -0.12065 -0.2794)
			(stroke
				(width 0.1)
				(type default)
			)
			(layer "F.Fab")
		)
		(fp_line
			(start -0.67945 -0.305054)
			(end -0.12065 -0.305054)
			(stroke
				(width 0.1)
				(type default)
			)
			(layer "F.Fab")
		)
		(fp_line
			(start 0.67945 -0.3048)
			(end 0.67945 0.3048)
			(stroke
				(width 0.1)
				(type default)
			)
			(layer "F.Fab")
		)
		(fp_line
			(start 0.12065 -0.3048)
			(end 0.67945 -0.3048)
			(stroke
				(width 0.1)
				(type default)
			)
			(layer "F.Fab")
		)
		(fp_line
			(start 0.12065 -0.2794)
			(end 0.12065 -0.3048)
			(stroke
				(width 0.1)
				(type default)
			)
			(layer "F.Fab")
		)
		(fp_line
			(start -0.12065 -0.2794)
			(end 0.12065 -0.2794)
			(stroke
				(width 0.1)
				(type default)
			)
			(layer "F.Fab")
		)
		(fp_line
			(start 0.120396 0.2794)
			(end -0.12065 0.2794)
			(stroke
				(width 0.1)
				(type default)
			)
			(layer "F.Fab")
		)
		(fp_line
			(start -0.12065 0.2794)
			(end -0.12065 0.3048)
			(stroke
				(width 0.1)
				(type default)
			)
			(layer "F.Fab")
		)
		(fp_line
			(start 0.67945 0.3048)
			(end 0.120396 0.3048)
			(stroke
				(width 0.1)
				(type default)
			)
			(layer "F.Fab")
		)
		(fp_line
			(start 0.120396 0.3048)
			(end 0.120396 0.2794)
			(stroke
				(width 0.1)
				(type default)
			)
			(layer "F.Fab")
		)
		(fp_line
			(start -0.12065 0.3048)
			(end -0.67945 0.3048)
			(stroke
				(width 0.1)
				(type default)
			)
			(layer "F.Fab")
		)
		(fp_line
			(start -0.67945 0.3048)
			(end -0.67945 -0.305054)
			(stroke
				(width 0.1)
				(type default)
			)
			(layer "F.Fab")
		)
		(pad "1" smd circle
			(at -0.40005 0 90)
			(size 0 0)
			(layers "F.Cu" "F.Mask" "F.Paste")
			(net "SW_PVDDIO_P1_BOOT4")
		)
		(pad "2" smd circle
			(at 0.40005 0 90)
			(size 0 0)
			(layers "F.Cu" "F.Mask" "F.Paste")
			(net "SW_PVDDIO_P1_BOOT4_R")
		)
	)
	(footprint ""
		(layer "F.Cu")
		(at 109.095794 -385.48056)
		(property "Reference" "R915"
			(at 0 0 0)
			(layer "F.SilkS")
			(hide yes)
			(effects
				(font
					(size 1.27 1.27)
				)
			)
		)
		(property "Value" ""
			(at 0 0 0)
			(layer "F.Fab")
			(effects
				(font
					(size 1.27 1.27)
				)
			)
		)
		(duplicate_pad_numbers_are_jumpers no)
		(fp_line
			(start -0.32512 -0.175006)
			(end 0.32512 -0.175006)
			(stroke
				(width 0.1)
				(type default)
			)
			(layer "F.Fab")
		)
		(fp_line
			(start -0.32512 0.175006)
			(end -0.32512 -0.175006)
			(stroke
				(width 0.1)
				(type default)
			)
			(layer "F.Fab")
		)
		(fp_line
			(start 0.32512 -0.175006)
			(end 0.32512 0.175006)
			(stroke
				(width 0.1)
				(type default)
			)
			(layer "F.Fab")
		)
		(fp_line
			(start 0.32512 0.175006)
			(end -0.32512 0.175006)
			(stroke
				(width 0.1)
				(type default)
			)
			(layer "F.Fab")
		)
		(pad "1" smd rect
			(at -0.2667 0)
			(size 0.3048 0.381)
			(layers "F.Cu" "F.Mask" "F.Paste")
			(net "P1V8_CPU1_RT_1D")
		)
		(pad "2" smd rect
			(at 0.2667 0 180)
			(size 0.3048 0.381)
			(layers "F.Cu" "F.Mask" "F.Paste")
			(net "GPIO2_RT_CPU1_P3")
		)
	)
)
